(kicad_pcb
	(version 20211014)
	(generator pcbnew)
	(general
    (thickness 1.6)
  )
	(paper "A4")
	(title_block
    (title "SA800U (Snapdragon 845) Baseboard")
    (date "2023-10-19")
    (rev "1.0.3")
    (company "Antmicro Ltd.")
    (comment 1 "www.antmicro.com")
		(comment 9 "footprints 306-312 of 589")
	)
	(layers
    (0 "F.Cu" signal)
    (1 "In1.Cu" power)
    (2 "In2.Cu" signal)
    (3 "In3.Cu" signal)
    (4 "In4.Cu" power)
    (31 "B.Cu" signal)
    (32 "B.Adhes" user "B.Adhesive")
    (33 "F.Adhes" user "F.Adhesive")
    (34 "B.Paste" user)
    (35 "F.Paste" user)
    (36 "B.SilkS" user "B.Silkscreen")
    (37 "F.SilkS" user "F.Silkscreen")
    (38 "B.Mask" user)
    (39 "F.Mask" user)
    (40 "Dwgs.User" user "User.Drawings")
    (41 "Cmts.User" user "User.Comments")
    (42 "Eco1.User" user "User.Eco1")
    (43 "Eco2.User" user "User.Eco2")
    (44 "Edge.Cuts" user)
    (45 "Margin" user)
    (46 "B.CrtYd" user "B.Courtyard")
    (47 "F.CrtYd" user "F.Courtyard")
    (48 "B.Fab" user)
    (49 "F.Fab" user)
  )
	(footprint "sa800u-baseboard-hw-footprints:PowerPak-1212" (layer "B.Cu")
    (tedit 625E61BE)
    (at 76.8 136.75 180)
    (property "Author" "Antmicro")
    (property "License" "Apache-2.0")
    (property "MPN" "SI7223DN-T1-GE3")
    (property "Manufacturer" "Vishay")
    (property "Sheetfile" "psu.kicad_sch")
    (property "Sheetname" "PSU")
    (attr smd)
    (fp_text reference "Q9" (at 0 2.5) (layer "B.SilkS")
      (effects (font (size 0.65 0.65) (thickness 0.15)) (justify mirror))
    )
    (fp_text value "Si7223DN" (at 0 -3) (layer "B.Fab") hide
      (effects (font (size 0.65 0.65) (thickness 0.15)) (justify mirror))
    )
    (fp_text user "Author: Antmicro" (at -2.667 -7.4) (layer "B.Fab") hide
      (effects (font (size 0.7 0.7) (thickness 0.15)) (justify left bottom mirror))
    )
    (fp_text user "${REFERENCE}" (at 0 0) (layer "B.Fab") hide
      (effects (font (size 0.65 0.65) (thickness 0.15)) (justify mirror))
    )
    (fp_text user "License: Apache-2.0" (at -2.667 -8.599) (layer "B.Fab") hide
      (effects (font (size 0.7 0.7) (thickness 0.15)) (justify left bottom mirror))
    )
    (fp_poly (pts
        (xy 1.699 -1.178)
        (xy 1.699 -0.771)
        (xy 1.14 -0.771)
        (xy 1.14 -0.528)
        (xy 1.699 -0.528)
        (xy 1.699 -0.121)
        (xy 1.14 -0.121)
        (xy 1.14 -0.174)
        (xy -0.387 -0.174)
        (xy -0.387 -1.119)
        (xy -0.386607 -1.698508)
        (xy -0.047 -1.699)
        (xy -0.047 -1.119)
        (xy 1.14 -1.119)
        (xy 1.14 -1.178)
      ) (layer "B.Paste") (width 0.1) (fill solid))
    (fp_poly (pts
        (xy 1.699 0.122)
        (xy 1.699 0.529)
        (xy 1.14 0.529)
        (xy 1.14 0.772)
        (xy 1.699 0.772)
        (xy 1.699 1.179)
        (xy 1.14 1.179)
        (xy 1.14 1.12)
        (xy -0.047 1.12)
        (xy -0.047 1.7)
        (xy -0.387 1.7)
        (xy -0.387 1.12)
        (xy -0.386607 0.174507)
        (xy 1.14 0.175)
        (xy 1.14 0.122)
      ) (layer "B.Paste") (width 0.1) (fill solid))
    (fp_line (start -1.702 -1.701) (end -1.702 -1.51) (layer "B.SilkS") (width 0.15))
    (fp_line (start -1.702 1.702) (end -0.6 1.7) (layer "B.SilkS") (width 0.15))
    (fp_line (start 1.701 -1.701) (end 0.2 -1.7) (layer "B.SilkS") (width 0.15))
    (fp_line (start -0.6 -1.7) (end -1.702 -1.701) (layer "B.SilkS") (width 0.15))
    (fp_line (start -1.702 1.511) (end -1.702 1.702) (layer "B.SilkS") (width 0.15))
    (fp_line (start 1.701 -1.51) (end 1.701 -1.701) (layer "B.SilkS") (width 0.15))
    (fp_line (start 1.701 1.702) (end 1.701 1.511) (layer "B.SilkS") (width 0.15))
    (fp_line (start 0.2 1.702) (end 1.701 1.702) (layer "B.SilkS") (width 0.15))
    (fp_circle (center -1.85 1.3) (end -1.8 1.3) (layer "B.SilkS") (width 0.15) (fill solid))
    (fp_poly (pts
        (xy -0.387 -0.174)
        (xy -0.387 -1.699)
        (xy -0.047 -1.699)
        (xy -0.047 -1.119)
        (xy 1.14 -1.119)
        (xy 1.14 -1.178)
        (xy 1.699 -1.178)
        (xy 1.699 -0.771)
        (xy 1.14 -0.771)
        (xy 1.14 -0.528)
        (xy 1.699 -0.528)
        (xy 1.699 -0.121)
        (xy 1.14 -0.121)
        (xy 1.14 -0.174)
      ) (layer "B.Mask") (width 0.1) (fill solid))
    (fp_poly (pts
        (xy 1.699 1.179)
        (xy 1.14 1.179)
        (xy 1.14 1.12)
        (xy -0.047 1.12)
        (xy -0.047 1.7)
        (xy -0.387 1.7)
        (xy -0.387 0.175)
        (xy 1.14 0.175)
        (xy 1.14 0.122)
        (xy 1.699 0.122)
        (xy 1.699 0.529)
        (xy 1.14 0.529)
        (xy 1.14 0.772)
        (xy 1.699 0.772)
      ) (layer "B.Mask") (width 0.1) (fill solid))
    (fp_line (start 1.95 -1.95) (end -1.96 -1.95) (layer "B.CrtYd") (width 0.05))
    (fp_line (start -1.96 -1.95) (end -1.96 1.96) (layer "B.CrtYd") (width 0.05))
    (fp_line (start 1.95 1.96) (end 1.95 -1.95) (layer "B.CrtYd") (width 0.05))
    (fp_line (start -1.96 1.96) (end 1.95 1.96) (layer "B.CrtYd") (width 0.05))
    (fp_line (start -1.575 1.575) (end 1.574 1.575) (layer "B.Fab") (width 0.15))
    (fp_line (start -1.575 -1.574) (end -1.575 1.575) (layer "B.Fab") (width 0.15))
    (fp_line (start 1.574 1.575) (end 1.574 -1.574) (layer "B.Fab") (width 0.15))
    (fp_line (start 1.574 -1.574) (end -1.575 -1.574) (layer "B.Fab") (width 0.15))
    (fp_circle (center 0.99 0.975) (end 0.914 0.975) (layer "B.Fab") (width 0.15) (fill none))
    (pad "1" smd rect (at -1.446 0.975 180) (size 0.508 0.4064) (layers "B.Cu" "B.Paste" "B.Mask")
      (net 157 "/PSU/VS1") (pinfunction "S1") (pintype "passive"))
    (pad "2" smd rect (at -1.446 0.325 180) (size 0.508 0.4064) (layers "B.Cu" "B.Paste" "B.Mask")
      (net 354 "/PSU/G1") (pinfunction "G1") (pintype "passive"))
    (pad "3" smd rect (at -1.446 -0.324 180) (size 0.508 0.4064) (layers "B.Cu" "B.Paste" "B.Mask")
      (net 157 "/PSU/VS1") (pinfunction "S2") (pintype "passive"))
    (pad "4" smd rect (at -1.446 -0.974 180) (size 0.508 0.4064) (layers "B.Cu" "B.Paste" "B.Mask")
      (net 354 "/PSU/G1") (pinfunction "G2") (pintype "passive"))
    (pad "5" smd rect (at 1.42 -0.974 180) (size 0.5588 0.4064) (layers "B.Cu" "B.Paste" "B.Mask")
      (net 152 "/PSU/AUX_VDD") (pinfunction "D2") (pintype "passive"))
    (pad "6" smd custom (at 1.42 -0.324 180) (size 0.5588 0.4064) (layers "B.Cu" "B.Paste" "B.Mask")
      (net 152 "/PSU/AUX_VDD") (pinfunction "D2") (pintype "passive") (zone_connect 2)
      (options (clearance outline) (anchor rect))
      (primitives
        (gr_poly (pts
            (xy 0.2794 -0.853186)
            (xy 0.2794 -0.446786)
            (xy -0.2794 -0.446786)
            (xy -0.2794 -0.2032)
            (xy 0.2794 -0.2032)
            (xy 0.2794 0.2032)
            (xy -0.2794 0.2032)
            (xy -0.279407 0.150493)
            (xy -1.806607 0.150493)
            (xy -1.806607 -1.374508)
            (xy -1.466602 -1.374508)
            (xy -1.466602 -0.794499)
            (xy -0.279407 -0.794507)
            (xy -0.2794 -0.853186)
          ) (width 0.1) (fill yes))
      ))
    (pad "7" smd custom (at 1.42 0.325 180) (size 0.5588 0.4064) (layers "B.Cu" "B.Paste" "B.Mask")
      (net 74 "VDD") (pinfunction "D1") (pintype "passive") (zone_connect 2)
      (options (clearance outline) (anchor rect))
      (primitives
        (gr_poly (pts
            (xy 0.2794 0.446786)
            (xy 0.2794 0.853186)
            (xy -0.2794 0.853186)
            (xy -0.279407 0.794507)
            (xy -1.466602 0.794499)
            (xy -1.466602 1.374508)
            (xy -1.806607 1.374508)
            (xy -1.806607 -0.150493)
            (xy -0.279407 -0.150493)
            (xy -0.2794 -0.2032)
            (xy 0.2794 -0.2032)
            (xy 0.2794 0.2032)
            (xy -0.2794 0.2032)
            (xy -0.2794 0.446786)
          ) (width 0.1) (fill yes))
      ))
    (pad "8" smd rect (at 1.42 0.975 180) (size 0.5588 0.4064) (layers "B.Cu" "B.Paste" "B.Mask")
      (net 74 "VDD") (pinfunction "D1") (pintype "passive"))
  )
	(footprint "sa800u-baseboard-hw-footprints:Vishay_PowerPAK_1212-8_Single" (layer "B.Cu")
    (tedit 61E93346)
    (at 78.7 117.6)
    (descr "PowerPAK 1212-8 Single")
    (tags "Vishay PowerPAK 1212-8 Single")
    (property "Author" "Antmicro")
    (property "License" "Apache-2.0")
    (property "MPN" "SQS401EN-T1_BE3")
    (property "Manufacturer" "Vishay")
    (property "Sheetfile" "psu.kicad_sch")
    (property "Sheetname" "PSU")
    (attr smd)
    (fp_text reference "Q16" (at 2.25 -1.84 180) (layer "B.SilkS")
      (effects (font (size 0.7 0.7) (thickness 0.15)) (justify left bottom mirror))
    )
    (fp_text value "SQS401EN-T1_BE3" (at -8 -2.7 180) (layer "B.Fab")
      (effects (font (size 0.7 0.7) (thickness 0.15)) (justify left bottom mirror))
    )
    (fp_text user "License: Apache-2.0" (at -8 -7.1 180) (layer "B.Fab") hide
      (effects (font (size 0.7 0.7) (thickness 0.15)) (justify left bottom mirror))
    )
    (fp_text user "Author: Antmicro" (at -8 -5.9 180) (layer "B.Fab") hide
      (effects (font (size 0.7 0.7) (thickness 0.15)) (justify left bottom mirror))
    )
    (fp_text user "${REFERENCE}" (at -8 -4.7 180) (layer "B.Fab") hide
      (effects (font (size 0.7 0.7) (thickness 0.15)) (justify left bottom mirror))
    )
    (fp_line (start -1.635 -1.3) (end -1.635 -1.634) (layer "B.SilkS") (width 0.15))
    (fp_line (start 1.634 -1.3) (end 1.634 -1.634) (layer "B.SilkS") (width 0.15))
    (fp_line (start -1.651 1.651) (end 1.648 1.651) (layer "B.SilkS") (width 0.15))
    (fp_line (start -1.635 -1.634) (end 1.634 -1.634) (layer "B.SilkS") (width 0.15))
    (fp_line (start -1.651 1.651) (end -1.651 1.317) (layer "B.SilkS") (width 0.15))
    (fp_line (start 1.648 1.651) (end 1.648 1.317) (layer "B.SilkS") (width 0.15))
    (fp_circle (center -1.9 1.4) (end -1.85 1.4) (layer "B.SilkS") (width 0.15) (fill solid))
    (fp_rect (start -2 1.8) (end 2 -1.798) (layer "B.CrtYd") (width 0.05) (fill none))
    (fp_line (start -1.6425 1.4175) (end -1.4175 1.6425) (layer "B.Fab") (width 0.15))
    (fp_rect (start -1.651 1.651) (end 1.648 -1.648) (layer "B.Fab") (width 0.15) (fill none))
    (pad "1" smd rect (at -1.436 0.99) (size 0.99 0.405) (layers "B.Cu" "B.Paste" "B.Mask")
      (net 74 "VDD") (pinfunction "S") (pintype "bidirectional"))
    (pad "2" smd rect (at -1.436 0.332) (size 0.99 0.405) (layers "B.Cu" "B.Paste" "B.Mask")
      (net 74 "VDD") (pinfunction "S") (pintype "bidirectional"))
    (pad "3" smd rect (at -1.436 -0.33) (size 0.99 0.405) (layers "B.Cu" "B.Paste" "B.Mask")
      (net 74 "VDD") (pinfunction "S") (pintype "bidirectional"))
    (pad "4" smd rect (at -1.436 -0.988) (size 0.99 0.405) (layers "B.Cu" "B.Paste" "B.Mask")
      (net 156 "/PSU/BYPASS_EN") (pinfunction "G") (pintype "bidirectional"))
    (pad "5" smd custom (at 0.557 0) (size 1.725 2.235) (layers "B.Cu" "B.Paste" "B.Mask")
      (net 133 "5V_SYS") (pinfunction "D") (pintype "bidirectional") (zone_connect 2)
      (options (clearance outline) (anchor rect))
      (primitives
        (gr_poly (pts
            (xy 0.8625 -0.1275)
            (xy 0.8625 0.1275)
            (xy 1.3725 0.1275)
            (xy 1.3725 0.5325)
            (xy 0.8625 0.5325)
            (xy 0.8625 0.7875)
            (xy 1.3725 0.7875)
            (xy 1.3725 1.195)
            (xy 0.6125 1.195)
            (xy 0.6125 -1.195)
            (xy 1.3725 -1.195)
            (xy 1.3725 -0.7875)
            (xy 0.8625 -0.7875)
            (xy 0.8625 -0.5325)
            (xy 1.3725 -0.5325)
            (xy 1.3725 -0.1275)
          ) (width 0) (fill yes))
      ))
  )
	(footprint "sa800u-baseboard-hw-footprints:R_0402_1005Metric" (layer "B.Cu")
    (tedit 5FD9C158)
    (at 148 83)
    (descr "Resistor SMD 0402")
    (tags "resistor SMD 0402")
    (property "Author" "Antmicro")
    (property "Current" "1A")
    (property "DNP" "DNP")
    (property "License" "Apache-2.0")
    (property "MPN" "ERJ2GE0R00X")
    (property "Manufacturer" "Panasonic")
    (property "Sheetfile" "sa800u-baseboard-hw.kicad_sch")
    (property "Sheetname" "")
    (property "Tolerance" "")
    (property "Val" "0R")
    (attr exclude_from_pos_files)
    (fp_text reference "R1" (at 0.6 1.37 180) (layer "B.SilkS")
      (effects (font (size 0.7 0.7) (thickness 0.15)) (justify left bottom mirror))
    )
    (fp_text value "R_0R_0402" (at 0 -1.4 180) (layer "B.Fab")
      (effects (font (size 0.7 0.7) (thickness 0.15)) (justify left bottom mirror))
    )
    (fp_text user "${REFERENCE}" (at -0.95 -3.168 180) (layer "B.Fab") hide
      (effects (font (size 0.7 0.7) (thickness 0.15)) (justify left bottom mirror))
    )
    (fp_text user "License: Apache-2.0" (at -0.95 -5.169 180) (layer "B.Fab") hide
      (effects (font (size 0.7 0.7) (thickness 0.15)) (justify left bottom mirror))
    )
    (fp_text user "Author: Antmicro" (at -0.95 -4.169 180) (layer "B.Fab") hide
      (effects (font (size 0.7 0.7) (thickness 0.15)) (justify left bottom mirror))
    )
    (fp_rect (start -0.93 0.47) (end 0.93 -0.47) (layer "B.CrtYd") (width 0.05) (fill none))
    (fp_rect (start -0.5 0.25) (end 0.5 -0.25) (layer "B.Fab") (width 0.15) (fill none))
    (pad "1" smd roundrect (at -0.485 0) (size 0.59 0.64) (layers "B.Cu" "B.Paste" "B.Mask") (roundrect_rratio 0.25)
      (net 1 "GND") (pintype "passive"))
    (pad "2" smd roundrect (at 0.485 0) (size 0.59 0.64) (layers "B.Cu" "B.Paste" "B.Mask") (roundrect_rratio 0.25)
      (net 392 "Net-(R1-Pad2)") (pintype "passive"))
  )
	(footprint "sa800u-baseboard-hw-footprints:R_0402_1005Metric" (layer "B.Cu")
    (tedit 5FD9C158)
    (at 61 151)
    (descr "Resistor SMD 0402")
    (tags "resistor SMD 0402")
    (property "Author" "Antmicro")
    (property "Current" "1A")
    (property "DNP" "DNP")
    (property "License" "Apache-2.0")
    (property "MPN" "ERJ2GE0R00X")
    (property "Manufacturer" "Panasonic")
    (property "Sheetfile" "sa800u-baseboard-hw.kicad_sch")
    (property "Sheetname" "")
    (property "Tolerance" "")
    (property "Val" "0R")
    (attr exclude_from_pos_files)
    (fp_text reference "R4" (at 0.74 -0.63 180) (layer "B.SilkS")
      (effects (font (size 0.7 0.7) (thickness 0.15)) (justify left bottom mirror))
    )
    (fp_text value "R_0R_0402" (at 0 -1.4 180) (layer "B.Fab")
      (effects (font (size 0.7 0.7) (thickness 0.15)) (justify left bottom mirror))
    )
    (fp_text user "License: Apache-2.0" (at -0.95 -5.169 180) (layer "B.Fab") hide
      (effects (font (size 0.7 0.7) (thickness 0.15)) (justify left bottom mirror))
    )
    (fp_text user "${REFERENCE}" (at -0.95 -3.168 180) (layer "B.Fab") hide
      (effects (font (size 0.7 0.7) (thickness 0.15)) (justify left bottom mirror))
    )
    (fp_text user "Author: Antmicro" (at -0.95 -4.169 180) (layer "B.Fab") hide
      (effects (font (size 0.7 0.7) (thickness 0.15)) (justify left bottom mirror))
    )
    (fp_rect (start -0.93 0.47) (end 0.93 -0.47) (layer "B.CrtYd") (width 0.05) (fill none))
    (fp_rect (start -0.5 0.25) (end 0.5 -0.25) (layer "B.Fab") (width 0.15) (fill none))
    (pad "1" smd roundrect (at -0.485 0) (size 0.59 0.64) (layers "B.Cu" "B.Paste" "B.Mask") (roundrect_rratio 0.25)
      (net 4 "Earth") (pintype "passive"))
    (pad "2" smd roundrect (at 0.485 0) (size 0.59 0.64) (layers "B.Cu" "B.Paste" "B.Mask") (roundrect_rratio 0.25)
      (net 39 "Net-(R4-Pad2)") (pintype "passive"))
  )
	(footprint "sa800u-baseboard-hw-footprints:R_0402_1005Metric" (layer "B.Cu")
    (tedit 5FD9C158)
    (at 68.75 85.5 180)
    (descr "Resistor SMD 0402")
    (tags "resistor SMD 0402")
    (property "Author" "Antmicro")
    (property "Current" "1A")
    (property "DNP" "DNP")
    (property "License" "Apache-2.0")
    (property "MPN" "ERJ2GE0R00X")
    (property "Manufacturer" "Panasonic")
    (property "Sheetfile" "sa800u-baseboard-hw.kicad_sch")
    (property "Sheetname" "")
    (property "Tolerance" "")
    (property "Val" "0R")
    (attr exclude_from_pos_files)
    (fp_text reference "R3" (at -0.57 0.68) (layer "B.SilkS")
      (effects (font (size 0.7 0.7) (thickness 0.15)) (justify left bottom mirror))
    )
    (fp_text value "R_0R_0402" (at 0 -1.4) (layer "B.Fab")
      (effects (font (size 0.7 0.7) (thickness 0.15)) (justify left bottom mirror))
    )
    (fp_text user "${REFERENCE}" (at -0.95 -3.168) (layer "B.Fab") hide
      (effects (font (size 0.7 0.7) (thickness 0.15)) (justify left bottom mirror))
    )
    (fp_text user "License: Apache-2.0" (at -0.95 -5.169) (layer "B.Fab") hide
      (effects (font (size 0.7 0.7) (thickness 0.15)) (justify left bottom mirror))
    )
    (fp_text user "Author: Antmicro" (at -0.95 -4.169) (layer "B.Fab") hide
      (effects (font (size 0.7 0.7) (thickness 0.15)) (justify left bottom mirror))
    )
    (fp_rect (start -0.93 0.47) (end 0.93 -0.47) (layer "B.CrtYd") (width 0.05) (fill none))
    (fp_rect (start -0.5 0.25) (end 0.5 -0.25) (layer "B.Fab") (width 0.15) (fill none))
    (pad "1" smd roundrect (at -0.485 0 180) (size 0.59 0.64) (layers "B.Cu" "B.Paste" "B.Mask") (roundrect_rratio 0.25)
      (net 1 "GND") (pintype "passive"))
    (pad "2" smd roundrect (at 0.485 0 180) (size 0.59 0.64) (layers "B.Cu" "B.Paste" "B.Mask") (roundrect_rratio 0.25)
      (net 38 "Net-(R3-Pad2)") (pintype "passive"))
  )
	(footprint "sa800u-baseboard-hw-footprints:R_0402_1005Metric" (layer "B.Cu")
    (tedit 5FD9C158)
    (at 131 108.1 180)
    (descr "Resistor SMD 0402")
    (tags "resistor SMD 0402")
    (property "Author" "Antmicro")
    (property "License" "Apache-2.0")
    (property "MPN" "CR0402-FX-2001GLF")
    (property "Manufacturer" "Bourns")
    (property "Sheetfile" "hdmi-converter.kicad_sch")
    (property "Sheetname" "HDMI converter")
    (property "Tolerance" "1%")
    (property "Val" "2k")
    (attr smd)
    (fp_text reference "R34" (at 0.86 -0.39) (layer "B.SilkS")
      (effects (font (size 0.7 0.7) (thickness 0.15)) (justify left bottom mirror))
    )
    (fp_text value "R_2k_0402" (at 0 -1.4) (layer "B.Fab")
      (effects (font (size 0.7 0.7) (thickness 0.15)) (justify left bottom mirror))
    )
    (fp_text user "License: Apache-2.0" (at -0.95 -5.169) (layer "B.Fab") hide
      (effects (font (size 0.7 0.7) (thickness 0.15)) (justify left bottom mirror))
    )
    (fp_text user "Author: Antmicro" (at -0.95 -4.169) (layer "B.Fab") hide
      (effects (font (size 0.7 0.7) (thickness 0.15)) (justify left bottom mirror))
    )
    (fp_text user "${REFERENCE}" (at -0.95 -3.168) (layer "B.Fab") hide
      (effects (font (size 0.7 0.7) (thickness 0.15)) (justify left bottom mirror))
    )
    (fp_rect (start -0.93 0.47) (end 0.93 -0.47) (layer "B.CrtYd") (width 0.05) (fill none))
    (fp_rect (start -0.5 0.25) (end 0.5 -0.25) (layer "B.Fab") (width 0.15) (fill none))
    (pad "1" smd roundrect (at -0.485 0 180) (size 0.59 0.64) (layers "B.Cu" "B.Paste" "B.Mask") (roundrect_rratio 0.25)
      (net 40 "I2C4_SDA") (pintype "passive"))
    (pad "2" smd roundrect (at 0.485 0 180) (size 0.59 0.64) (layers "B.Cu" "B.Paste" "B.Mask") (roundrect_rratio 0.25)
      (net 132 "VREG_S4A_1V8") (pintype "passive"))
  )
	(footprint "sa800u-baseboard-hw-footprints:R_0402_1005Metric" (layer "B.Cu")
    (tedit 5FD9C158)
    (at 131 107.1 180)
    (descr "Resistor SMD 0402")
    (tags "resistor SMD 0402")
    (property "Author" "Antmicro")
    (property "License" "Apache-2.0")
    (property "MPN" "CR0402-FX-2001GLF")
    (property "Manufacturer" "Bourns")
    (property "Sheetfile" "hdmi-converter.kicad_sch")
    (property "Sheetname" "HDMI converter")
    (property "Tolerance" "1%")
    (property "Val" "2k")
    (attr smd)
    (fp_text reference "R36" (at 0.86 -0.39) (layer "B.SilkS")
      (effects (font (size 0.7 0.7) (thickness 0.15)) (justify left bottom mirror))
    )
    (fp_text value "R_2k_0402" (at 0 -1.4) (layer "B.Fab")
      (effects (font (size 0.7 0.7) (thickness 0.15)) (justify left bottom mirror))
    )
    (fp_text user "License: Apache-2.0" (at -0.95 -5.169) (layer "B.Fab") hide
      (effects (font (size 0.7 0.7) (thickness 0.15)) (justify left bottom mirror))
    )
    (fp_text user "Author: Antmicro" (at -0.95 -4.169) (layer "B.Fab") hide
      (effects (font (size 0.7 0.7) (thickness 0.15)) (justify left bottom mirror))
    )
    (fp_text user "${REFERENCE}" (at -0.95 -3.168) (layer "B.Fab") hide
      (effects (font (size 0.7 0.7) (thickness 0.15)) (justify left bottom mirror))
    )
    (fp_rect (start -0.93 0.47) (end 0.93 -0.47) (layer "B.CrtYd") (width 0.05) (fill none))
    (fp_rect (start -0.5 0.25) (end 0.5 -0.25) (layer "B.Fab") (width 0.15) (fill none))
    (pad "1" smd roundrect (at -0.485 0 180) (size 0.59 0.64) (layers "B.Cu" "B.Paste" "B.Mask") (roundrect_rratio 0.25)
      (net 41 "I2C4_SCL") (pintype "passive"))
    (pad "2" smd roundrect (at 0.485 0 180) (size 0.59 0.64) (layers "B.Cu" "B.Paste" "B.Mask") (roundrect_rratio 0.25)
      (net 132 "VREG_S4A_1V8") (pintype "passive"))
  )
)
